(kicad_pcb
	(version 20260206)
	(generator "pcbnew")
	(generator_version "10.0")
	(general
		(thickness 1.6)
		(legacy_teardrops no)
	)
	(paper "A4")
	(title_block
		(title "01162023_DA0F0TEBIF0_F0T_Expander_BD_F_brd_V02_OCP.brd")
		(comment 1 "Grand Teton / footprints 8049-8056 of 9728")
	)
	(layers
		(0 "F.Cu" signal "TOP")
		(4 "In1.Cu" signal "GND")
		(6 "In2.Cu" signal "VCC")
		(8 "In3.Cu" signal "VCC1")
		(10 "In4.Cu" signal "GND1")
		(12 "In5.Cu" signal "IN1")
		(14 "In6.Cu" signal "GND2")
		(16 "In7.Cu" signal "IN2")
		(18 "In8.Cu" signal "GND3")
		(20 "In9.Cu" signal "IN3")
		(22 "In10.Cu" signal "GND4")
		(24 "In11.Cu" signal "IN4")
		(26 "In12.Cu" signal "GND5")
		(28 "In13.Cu" signal "IN5")
		(30 "In14.Cu" signal "GND6")
		(32 "In15.Cu" signal "IN6")
		(34 "In16.Cu" signal "GND7")
		(2 "B.Cu" signal "BOTTOM")
		(9 "F.Adhes" user "F.Adhesive")
		(11 "B.Adhes" user "B.Adhesive")
		(13 "F.Paste" user "Package Geometry/Pastemask Top")
		(15 "B.Paste" user "Package Geometry/Pastemask Bottom")
		(5 "F.SilkS" user "Ref Des/Silkscreen Top")
		(7 "B.SilkS" user "Ref Des/Silkscreen Bottom")
		(1 "F.Mask" user "Board Geometry/Soldermask Top")
		(3 "B.Mask" user "Board Geometry/Soldermask Bottom")
		(17 "Dwgs.User" user "User.Drawings")
		(19 "Cmts.User" user "User.Comments")
		(21 "Eco1.User" user "User.Eco1")
		(23 "Eco2.User" user "User.Eco2")
		(25 "Edge.Cuts" user "Board Geometry/Outline")
		(27 "Margin" user)
		(31 "F.CrtYd" user "Package Geometry/Place Bound Top")
		(29 "B.CrtYd" user "Package Geometry/Place Bound Bottom")
		(35 "F.Fab" user "Ref Des/Assembly Top")
		(33 "B.Fab" user "Ref Des/Assembly Bottom")
	)
	(footprint ""
		(layer "B.Cu")
		(at 292.32479 -297.79976 90)
		(property "Reference" "C1651"
			(at 0 0 90)
			(layer "B.SilkS")
			(hide yes)
			(effects
				(font
					(size 1.27 1.27)
				)
				(justify mirror)
			)
		)
		(property "Value" ""
			(at 0 0 90)
			(layer "B.Fab")
			(effects
				(font
					(size 1.27 1.27)
				)
				(justify mirror)
			)
		)
		(duplicate_pad_numbers_are_jumpers no)
		(fp_line
			(start 0.299974 -0.150114)
			(end -0.299974 -0.150114)
			(stroke
				(width 0.1)
				(type default)
			)
			(layer "B.Fab")
		)
		(fp_line
			(start -0.299974 -0.150114)
			(end -0.299974 0.150114)
			(stroke
				(width 0.1)
				(type default)
			)
			(layer "B.Fab")
		)
		(fp_line
			(start 0.299974 0.150114)
			(end 0.299974 -0.150114)
			(stroke
				(width 0.1)
				(type default)
			)
			(layer "B.Fab")
		)
		(fp_line
			(start -0.299974 0.150114)
			(end 0.299974 0.150114)
			(stroke
				(width 0.1)
				(type default)
			)
			(layer "B.Fab")
		)
		(pad "1" smd rect
			(at 0.2667 0 270)
			(size 0.3048 0.381)
			(layers "B.Cu" "B.Mask" "B.Paste")
			(net "P0V8_PEX2")
		)
		(pad "2" smd rect
			(at -0.2667 0 270)
			(size 0.3048 0.381)
			(layers "B.Cu" "B.Mask" "B.Paste")
			(net "GND")
		)
	)
	(footprint ""
		(layer "B.Cu")
		(at 406.470104 -305.399948 -90)
		(property "Reference" "C3497"
			(at 0 0 90)
			(layer "B.SilkS")
			(hide yes)
			(effects
				(font
					(size 1.27 1.27)
				)
				(justify mirror)
			)
		)
		(property "Value" ""
			(at 0 0 90)
			(layer "B.Fab")
			(effects
				(font
					(size 1.27 1.27)
				)
				(justify mirror)
			)
		)
		(duplicate_pad_numbers_are_jumpers no)
		(fp_line
			(start -0.299974 0.150114)
			(end 0.299974 0.150114)
			(stroke
				(width 0.1)
				(type default)
			)
			(layer "B.Fab")
		)
		(fp_line
			(start 0.299974 0.150114)
			(end 0.299974 -0.150114)
			(stroke
				(width 0.1)
				(type default)
			)
			(layer "B.Fab")
		)
		(fp_line
			(start -0.299974 -0.150114)
			(end -0.299974 0.150114)
			(stroke
				(width 0.1)
				(type default)
			)
			(layer "B.Fab")
		)
		(fp_line
			(start 0.299974 -0.150114)
			(end -0.299974 -0.150114)
			(stroke
				(width 0.1)
				(type default)
			)
			(layer "B.Fab")
		)
		(pad "1" smd rect
			(at 0.2667 0 90)
			(size 0.3048 0.381)
			(layers "B.Cu" "B.Mask" "B.Paste")
			(net "P1V25_SERDES_VDDPLL_PEX3")
		)
		(pad "2" smd rect
			(at -0.2667 0 90)
			(size 0.3048 0.381)
			(layers "B.Cu" "B.Mask" "B.Paste")
			(net "GND")
		)
	)
	(footprint ""
		(layer "B.Cu")
		(at 231.86771 -220.704156)
		(property "Reference" "C3611"
			(at 0 0 0)
			(layer "B.SilkS")
			(hide yes)
			(effects
				(font
					(size 1.27 1.27)
				)
				(justify mirror)
			)
		)
		(property "Value" ""
			(at 0 0 0)
			(layer "B.Fab")
			(effects
				(font
					(size 1.27 1.27)
				)
				(justify mirror)
			)
		)
		(duplicate_pad_numbers_are_jumpers no)
		(fp_line
			(start -0.69215 -0.2921)
			(end -0.69215 0.2921)
			(stroke
				(width 0.1524)
				(type default)
			)
			(layer "B.SilkS")
		)
		(fp_line
			(start -0.69215 0.2921)
			(end 0.69215 0.2921)
			(stroke
				(width 0.1524)
				(type default)
			)
			(layer "B.SilkS")
		)
		(fp_line
			(start 0.69215 -0.2921)
			(end -0.69215 -0.2921)
			(stroke
				(width 0.1524)
				(type default)
			)
			(layer "B.SilkS")
		)
		(fp_line
			(start 0.69215 0.2921)
			(end 0.69215 -0.2921)
			(stroke
				(width 0.1524)
				(type default)
			)
			(layer "B.SilkS")
		)
		(fp_line
			(start -0.51435 -0.2794)
			(end -0.51435 0.2794)
			(stroke
				(width 0.1)
				(type default)
			)
			(layer "B.Fab")
		)
		(fp_line
			(start -0.51435 0.2794)
			(end 0.51435 0.2794)
			(stroke
				(width 0.1)
				(type default)
			)
			(layer "B.Fab")
		)
		(fp_line
			(start 0.51435 -0.2794)
			(end -0.51435 -0.2794)
			(stroke
				(width 0.1)
				(type default)
			)
			(layer "B.Fab")
		)
		(fp_line
			(start 0.51435 0.2794)
			(end 0.51435 -0.2794)
			(stroke
				(width 0.1)
				(type default)
			)
			(layer "B.Fab")
		)
		(pad "1" smd circle
			(at 0.40005 0 180)
			(size 0 0)
			(layers "B.Cu" "B.Mask" "B.Paste")
			(net "P3V3_BIC_ADCAV33")
		)
		(pad "2" smd circle
			(at -0.40005 0 180)
			(size 0 0)
			(layers "B.Cu" "B.Mask" "B.Paste")
			(net "GND")
		)
		(zone
			(layer "B.Cu")
			(hatch none 0.5)
			(connect_pads
				(clearance 0)
			)
			(min_thickness 0.25)
			(keepout
				(tracks not_allowed)
				(vias allowed)
				(pads allowed)
				(copperpour not_allowed)
				(footprints allowed)
			)
			(placement
				(enabled no)
				(sheetname "")
			)
			(fill
				(thermal_gap 0.5)
				(thermal_bridge_width 0.5)
				(island_removal_mode 0)
			)
			(polygon
				(pts
					(xy 232.05821 -220.616526) (xy 231.96677 -220.55836) (xy 231.76738 -220.55836) (xy 231.67721 -220.616526)
					(xy 231.67721 -220.791786) (xy 231.76738 -220.850206) (xy 231.96677 -220.850206) (xy 232.05821 -220.79204)
				)
			)
		)
	)
	(footprint ""
		(layer "B.Cu")
		(at 400.349974 -292.099746 90)
		(property "Reference" "C1942"
			(at 0 0 90)
			(layer "B.SilkS")
			(hide yes)
			(effects
				(font
					(size 1.27 1.27)
				)
				(justify mirror)
			)
		)
		(property "Value" ""
			(at 0 0 90)
			(layer "B.Fab")
			(effects
				(font
					(size 1.27 1.27)
				)
				(justify mirror)
			)
		)
		(duplicate_pad_numbers_are_jumpers no)
		(fp_line
			(start 0.299974 -0.150114)
			(end -0.299974 -0.150114)
			(stroke
				(width 0.1)
				(type default)
			)
			(layer "B.Fab")
		)
		(fp_line
			(start -0.299974 -0.150114)
			(end -0.299974 0.150114)
			(stroke
				(width 0.1)
				(type default)
			)
			(layer "B.Fab")
		)
		(fp_line
			(start 0.299974 0.150114)
			(end 0.299974 -0.150114)
			(stroke
				(width 0.1)
				(type default)
			)
			(layer "B.Fab")
		)
		(fp_line
			(start -0.299974 0.150114)
			(end 0.299974 0.150114)
			(stroke
				(width 0.1)
				(type default)
			)
			(layer "B.Fab")
		)
		(pad "1" smd rect
			(at 0.2667 0 270)
			(size 0.3048 0.381)
			(layers "B.Cu" "B.Mask" "B.Paste")
			(net "P0V8_SERDES_VDDA_PEX3")
		)
		(pad "2" smd rect
			(at -0.2667 0 270)
			(size 0.3048 0.381)
			(layers "B.Cu" "B.Mask" "B.Paste")
			(net "GND")
		)
	)
	(footprint ""
		(layer "B.Cu")
		(at 139.275058 -228.346 90)
		(property "Reference" "R3460"
			(at 0 0 90)
			(layer "B.SilkS")
			(hide yes)
			(effects
				(font
					(size 1.27 1.27)
				)
				(justify mirror)
			)
		)
		(property "Value" ""
			(at 0 0 90)
			(layer "B.Fab")
			(effects
				(font
					(size 1.27 1.27)
				)
				(justify mirror)
			)
		)
		(duplicate_pad_numbers_are_jumpers no)
		(fp_line
			(start 0.7874 -0.4064)
			(end -0.7874 -0.4064)
			(stroke
				(width 0.1524)
				(type default)
			)
			(layer "B.SilkS")
		)
		(fp_line
			(start -0.7874 -0.4064)
			(end -0.7874 0.4064)
			(stroke
				(width 0.1524)
				(type default)
			)
			(layer "B.SilkS")
		)
		(fp_line
			(start 0.7874 0.4064)
			(end 0.7874 -0.4064)
			(stroke
				(width 0.1524)
				(type default)
			)
			(layer "B.SilkS")
		)
		(fp_line
			(start -0.7874 0.4064)
			(end 0.7874 0.4064)
			(stroke
				(width 0.1524)
				(type default)
			)
			(layer "B.SilkS")
		)
		(fp_line
			(start 0.67945 -0.305054)
			(end 0.12065 -0.305054)
			(stroke
				(width 0.1)
				(type default)
			)
			(layer "B.Fab")
		)
		(fp_line
			(start 0.12065 -0.305054)
			(end 0.12065 -0.2794)
			(stroke
				(width 0.1)
				(type default)
			)
			(layer "B.Fab")
		)
		(fp_line
			(start -0.12065 -0.3048)
			(end -0.67945 -0.3048)
			(stroke
				(width 0.1)
				(type default)
			)
			(layer "B.Fab")
		)
		(fp_line
			(start -0.67945 -0.3048)
			(end -0.67945 0.3048)
			(stroke
				(width 0.1)
				(type default)
			)
			(layer "B.Fab")
		)
		(fp_line
			(start 0.12065 -0.2794)
			(end -0.12065 -0.2794)
			(stroke
				(width 0.1)
				(type default)
			)
			(layer "B.Fab")
		)
		(fp_line
			(start -0.12065 -0.2794)
			(end -0.12065 -0.3048)
			(stroke
				(width 0.1)
				(type default)
			)
			(layer "B.Fab")
		)
		(fp_line
			(start 0.12065 0.2794)
			(end 0.12065 0.3048)
			(stroke
				(width 0.1)
				(type default)
			)
			(layer "B.Fab")
		)
		(fp_line
			(start -0.120396 0.2794)
			(end 0.12065 0.2794)
			(stroke
				(width 0.1)
				(type default)
			)
			(layer "B.Fab")
		)
		(fp_line
			(start 0.67945 0.3048)
			(end 0.67945 -0.305054)
			(stroke
				(width 0.1)
				(type default)
			)
			(layer "B.Fab")
		)
		(fp_line
			(start 0.12065 0.3048)
			(end 0.67945 0.3048)
			(stroke
				(width 0.1)
				(type default)
			)
			(layer "B.Fab")
		)
		(fp_line
			(start -0.120396 0.3048)
			(end -0.120396 0.2794)
			(stroke
				(width 0.1)
				(type default)
			)
			(layer "B.Fab")
		)
		(fp_line
			(start -0.67945 0.3048)
			(end -0.120396 0.3048)
			(stroke
				(width 0.1)
				(type default)
			)
			(layer "B.Fab")
		)
		(pad "1" smd circle
			(at 0.40005 0 270)
			(size 0 0)
			(layers "B.Cu" "B.Mask" "B.Paste")
			(net "SPI_PEX1_SDIO1_MUX_R")
		)
		(pad "2" smd circle
			(at -0.40005 0 270)
			(size 0 0)
			(layers "B.Cu" "B.Mask" "B.Paste")
			(net "SPI_PEX1_SDIO1_MUX")
		)
	)
	(footprint ""
		(layer "B.Cu")
		(at 181.92496 -297.79976 90)
		(property "Reference" "C1369"
			(at 0 0 90)
			(layer "B.SilkS")
			(hide yes)
			(effects
				(font
					(size 1.27 1.27)
				)
				(justify mirror)
			)
		)
		(property "Value" ""
			(at 0 0 90)
			(layer "B.Fab")
			(effects
				(font
					(size 1.27 1.27)
				)
				(justify mirror)
			)
		)
		(duplicate_pad_numbers_are_jumpers no)
		(fp_line
			(start 0.299974 -0.150114)
			(end -0.299974 -0.150114)
			(stroke
				(width 0.1)
				(type default)
			)
			(layer "B.Fab")
		)
		(fp_line
			(start -0.299974 -0.150114)
			(end -0.299974 0.150114)
			(stroke
				(width 0.1)
				(type default)
			)
			(layer "B.Fab")
		)
		(fp_line
			(start 0.299974 0.150114)
			(end 0.299974 -0.150114)
			(stroke
				(width 0.1)
				(type default)
			)
			(layer "B.Fab")
		)
		(fp_line
			(start -0.299974 0.150114)
			(end 0.299974 0.150114)
			(stroke
				(width 0.1)
				(type default)
			)
			(layer "B.Fab")
		)
		(pad "1" smd rect
			(at 0.2667 0 270)
			(size 0.3048 0.381)
			(layers "B.Cu" "B.Mask" "B.Paste")
			(net "P0V8_PEX1")
		)
		(pad "2" smd rect
			(at -0.2667 0 270)
			(size 0.3048 0.381)
			(layers "B.Cu" "B.Mask" "B.Paste")
			(net "GND")
		)
	)
	(footprint ""
		(layer "B.Cu")
		(at 305.149758 -297.79976 180)
		(property "Reference" "C3295"
			(at 0 0 0)
			(layer "B.SilkS")
			(hide yes)
			(effects
				(font
					(size 1.27 1.27)
				)
				(justify mirror)
			)
		)
		(property "Value" ""
			(at 0 0 0)
			(layer "B.Fab")
			(effects
				(font
					(size 1.27 1.27)
				)
				(justify mirror)
			)
		)
		(duplicate_pad_numbers_are_jumpers no)
		(fp_line
			(start 0.299974 0.150114)
			(end 0.299974 -0.150114)
			(stroke
				(width 0.1)
				(type default)
			)
			(layer "B.Fab")
		)
		(fp_line
			(start 0.299974 -0.150114)
			(end -0.299974 -0.150114)
			(stroke
				(width 0.1)
				(type default)
			)
			(layer "B.Fab")
		)
		(fp_line
			(start -0.299974 0.150114)
			(end 0.299974 0.150114)
			(stroke
				(width 0.1)
				(type default)
			)
			(layer "B.Fab")
		)
		(fp_line
			(start -0.299974 -0.150114)
			(end -0.299974 0.150114)
			(stroke
				(width 0.1)
				(type default)
			)
			(layer "B.Fab")
		)
		(pad "1" smd rect
			(at 0.2667 0)
			(size 0.3048 0.381)
			(layers "B.Cu" "B.Mask" "B.Paste")
			(net "P1V25_SERDES_VDDPLL_PEX2")
		)
		(pad "2" smd rect
			(at -0.2667 0)
			(size 0.3048 0.381)
			(layers "B.Cu" "B.Mask" "B.Paste")
			(net "GND")
		)
	)
	(footprint ""
		(layer "B.Cu")
		(at 379.365002 -221.066106)
		(property "Reference" "R930"
			(at 0 0 0)
			(layer "B.SilkS")
			(hide yes)
			(effects
				(font
					(size 1.27 1.27)
				)
				(justify mirror)
			)
		)
		(property "Value" ""
			(at 0 0 0)
			(layer "B.Fab")
			(effects
				(font
					(size 1.27 1.27)
				)
				(justify mirror)
			)
		)
		(duplicate_pad_numbers_are_jumpers no)
		(fp_line
			(start -0.7874 -0.4064)
			(end -0.7874 0.4064)
			(stroke
				(width 0.1524)
				(type default)
			)
			(layer "B.SilkS")
		)
		(fp_line
			(start -0.7874 0.4064)
			(end 0.7874 0.4064)
			(stroke
				(width 0.1524)
				(type default)
			)
			(layer "B.SilkS")
		)
		(fp_line
			(start 0.7874 -0.4064)
			(end -0.7874 -0.4064)
			(stroke
				(width 0.1524)
				(type default)
			)
			(layer "B.SilkS")
		)
		(fp_line
			(start 0.7874 0.4064)
			(end 0.7874 -0.4064)
			(stroke
				(width 0.1524)
				(type default)
			)
			(layer "B.SilkS")
		)
		(fp_line
			(start -0.67945 -0.3048)
			(end -0.67945 0.3048)
			(stroke
				(width 0.1)
				(type default)
			)
			(layer "B.Fab")
		)
		(fp_line
			(start -0.67945 0.3048)
			(end -0.120396 0.3048)
			(stroke
				(width 0.1)
				(type default)
			)
			(layer "B.Fab")
		)
		(fp_line
			(start -0.12065 -0.3048)
			(end -0.67945 -0.3048)
			(stroke
				(width 0.1)
				(type default)
			)
			(layer "B.Fab")
		)
		(fp_line
			(start -0.12065 -0.2794)
			(end -0.12065 -0.3048)
			(stroke
				(width 0.1)
				(type default)
			)
			(layer "B.Fab")
		)
		(fp_line
			(start -0.120396 0.2794)
			(end 0.12065 0.2794)
			(stroke
				(width 0.1)
				(type default)
			)
			(layer "B.Fab")
		)
		(fp_line
			(start -0.120396 0.3048)
			(end -0.120396 0.2794)
			(stroke
				(width 0.1)
				(type default)
			)
			(layer "B.Fab")
		)
		(fp_line
			(start 0.12065 -0.305054)
			(end 0.12065 -0.2794)
			(stroke
				(width 0.1)
				(type default)
			)
			(layer "B.Fab")
		)
		(fp_line
			(start 0.12065 -0.2794)
			(end -0.12065 -0.2794)
			(stroke
				(width 0.1)
				(type default)
			)
			(layer "B.Fab")
		)
		(fp_line
			(start 0.12065 0.2794)
			(end 0.12065 0.3048)
			(stroke
				(width 0.1)
				(type default)
			)
			(layer "B.Fab")
		)
		(fp_line
			(start 0.12065 0.3048)
			(end 0.67945 0.3048)
			(stroke
				(width 0.1)
				(type default)
			)
			(layer "B.Fab")
		)
		(fp_line
			(start 0.67945 -0.305054)
			(end 0.12065 -0.305054)
			(stroke
				(width 0.1)
				(type default)
			)
			(layer "B.Fab")
		)
		(fp_line
			(start 0.67945 0.3048)
			(end 0.67945 -0.305054)
			(stroke
				(width 0.1)
				(type default)
			)
			(layer "B.Fab")
		)
		(pad "1" smd circle
			(at 0.40005 0 180)
			(size 0 0)
			(layers "B.Cu" "B.Mask" "B.Paste")
			(net "UART_PEX1_SDB_BUF_R_RX")
		)
		(pad "2" smd circle
			(at -0.40005 0 180)
			(size 0 0)
			(layers "B.Cu" "B.Mask" "B.Paste")
			(net "UART_PEX1_SDB_BUF_RX")
		)
	)
)
